# BASEBOARD_FAB2 (Tioga Pass) — schematic netlist excerpt (pin names and nets, part order shuffled) for the footprints in the layout excerpt that follows; sources: Cadence DE-HDL packaged netlist, KiCad conversion of Wiwynn_Tioga_Pass_MB.brd

C3P47  CAP_A  0.1UF 16V 10% X7R  pkg 0402V  page 192 : A = P3V3_STBY ; B = GND
R2P18  RES  10.0K 1% CHIP  pkg 0402  page 196 : A = P3V3_STBY ; B = PWRGD_P5V_N
C2M15  CAP  0.22UF 16V 10% X7R  pkg 0402  page 106 : A = P3E_CPU0_PE3_OCP_TXN<8> ; B = P3E_OCP_CPU0_PE3_C_TXN<8>

(kicad_pcb
	(version 20260206)
	(generator "pcbnew")
	(generator_version "10.0")
	(general
		(thickness 1.6)
		(legacy_teardrops no)
	)
	(paper "A4")
	(title_block
		(title "Wiwynn_Tioga_Pass_MB.brd")
		(comment 1 "Tioga Pass / footprints 4376-4378 of 4770")
	)
	(layers
		(0 "F.Cu" signal "TOP")
		(4 "In1.Cu" signal "L2GND")
		(6 "In2.Cu" signal "L3")
		(8 "In3.Cu" signal "L4GND")
		(10 "In4.Cu" signal "L5")
		(12 "In5.Cu" signal "L6GND")
		(14 "In6.Cu" signal "L7VCC")
		(16 "In7.Cu" signal "L8VCC")
		(18 "In8.Cu" signal "L9GND")
		(20 "In9.Cu" signal "L10")
		(22 "In10.Cu" signal "L11GND")
		(24 "In11.Cu" signal "L12")
		(26 "In12.Cu" signal "L13GND")
		(2 "B.Cu" signal "BOTTOM")
		(9 "F.Adhes" user "F.Adhesive")
		(11 "B.Adhes" user "B.Adhesive")
		(13 "F.Paste" user "Package Geometry/Pastemask Top")
		(15 "B.Paste" user "Package Geometry/Pastemask Bottom")
		(5 "F.SilkS" user "Ref Des/Silkscreen Top")
		(7 "B.SilkS" user "Ref Des/Silkscreen Bottom")
		(1 "F.Mask" user "Board Geometry/Soldermask Top")
		(3 "B.Mask" user "Board Geometry/Soldermask Bottom")
		(17 "Dwgs.User" user "User.Drawings")
		(19 "Cmts.User" user "User.Comments")
		(21 "Eco1.User" user "User.Eco1")
		(23 "Eco2.User" user "User.Eco2")
		(25 "Edge.Cuts" user "Board Geometry/Outline")
		(27 "Margin" user)
		(31 "F.CrtYd" user "Package Geometry/Place Bound Top")
		(29 "B.CrtYd" user "Package Geometry/Place Bound Bottom")
		(35 "F.Fab" user "Ref Des/Assembly Top")
		(33 "B.Fab" user "Ref Des/Assembly Bottom")
	)
	(footprint ""
		(layer "B.Cu")
		(at 442.849 -116.49202)
		(property "Reference" "C2M15"
			(at 0 0 0)
			(layer "B.SilkS")
			(hide yes)
			(effects
				(font
					(size 1.27 1.27)
				)
				(justify mirror)
			)
		)
		(property "Value" ""
			(at 0 0 0)
			(layer "B.Fab")
			(effects
				(font
					(size 1.27 1.27)
				)
				(justify mirror)
			)
		)
		(duplicate_pad_numbers_are_jumpers no)
		(fp_rect
			(start -0.3048 0.9906)
			(end 0.3048 -0.1016)
			(stroke
				(width 0)
				(type default)
			)
			(fill no)
			(layer "B.CrtYd")
		)
		(fp_line
			(start -0.3048 -0.1016)
			(end 0.3048 -0.1016)
			(stroke
				(width 0.1)
				(type default)
			)
			(layer "B.Fab")
		)
		(fp_line
			(start -0.3048 0.9906)
			(end -0.3048 -0.1016)
			(stroke
				(width 0.1)
				(type default)
			)
			(layer "B.Fab")
		)
		(fp_line
			(start 0.3048 -0.1016)
			(end 0.3048 0.9906)
			(stroke
				(width 0.1)
				(type default)
			)
			(layer "B.Fab")
		)
		(fp_line
			(start 0.3048 0.9906)
			(end -0.3048 0.9906)
			(stroke
				(width 0.1)
				(type default)
			)
			(layer "B.Fab")
		)
		(pad "1" smd rect
			(at 0 0 180)
			(size 0.508 0.508)
			(layers "B.Cu" "B.Mask" "B.Paste")
			(net "P3E_CPU0_PE3_OCP_TXN<8>")
		)
		(pad "2" smd rect
			(at 0 0.889 180)
			(size 0.508 0.508)
			(layers "B.Cu" "B.Mask" "B.Paste")
			(net "P3E_OCP_CPU0_PE3_C_TXN<8>")
		)
		(zone
			(layer "B.Cu")
			(hatch none 0.5)
			(connect_pads
				(clearance 0)
			)
			(min_thickness 0.25)
			(keepout
				(tracks not_allowed)
				(vias allowed)
				(pads allowed)
				(copperpour not_allowed)
				(footprints allowed)
			)
			(placement
				(enabled no)
				(sheetname "")
			)
			(fill
				(thermal_gap 0.5)
				(thermal_bridge_width 0.5)
				(island_removal_mode 0)
			)
			(polygon
				(pts
					(xy 442.595 -115.85702) (xy 443.103 -115.85702) (xy 443.103 -116.23802) (xy 442.595 -116.23802)
				)
			)
		)
		(zone
			(layer "B.Cu")
			(hatch none 0.5)
			(connect_pads
				(clearance 0)
			)
			(min_thickness 0.25)
			(keepout
				(tracks allowed)
				(vias not_allowed)
				(pads allowed)
				(copperpour not_allowed)
				(footprints allowed)
			)
			(placement
				(enabled no)
				(sheetname "")
			)
			(fill
				(thermal_gap 0.5)
				(thermal_bridge_width 0.5)
				(island_removal_mode 0)
			)
			(polygon
				(pts
					(xy 442.595 -115.85702) (xy 443.103 -115.85702) (xy 443.103 -116.23802) (xy 442.595 -116.23802)
				)
			)
		)
	)
	(footprint ""
		(layer "B.Cu")
		(at 411.861 -6.5405)
		(property "Reference" "R2P18"
			(at 0 0 0)
			(layer "B.SilkS")
			(hide yes)
			(effects
				(font
					(size 1.27 1.27)
				)
				(justify mirror)
			)
		)
		(property "Value" ""
			(at 0 0 0)
			(layer "B.Fab")
			(effects
				(font
					(size 1.27 1.27)
				)
				(justify mirror)
			)
		)
		(duplicate_pad_numbers_are_jumpers no)
		(fp_poly
			(pts
				(xy 0.2794 -0.1016) (xy -0.2794 -0.1016) (xy -0.2794 0.9906) (xy 0.2794 0.9906)
			)
			(stroke
				(width 0)
				(type default)
			)
			(fill no)
			(layer "B.CrtYd")
		)
		(fp_line
			(start -0.2794 -0.1016)
			(end 0.2794 -0.1016)
			(stroke
				(width 0.1)
				(type default)
			)
			(layer "B.Fab")
		)
		(fp_line
			(start -0.2794 0.9906)
			(end -0.2794 -0.1016)
			(stroke
				(width 0.1)
				(type default)
			)
			(layer "B.Fab")
		)
		(fp_line
			(start 0.2794 -0.1016)
			(end 0.2794 0.9906)
			(stroke
				(width 0.1)
				(type default)
			)
			(layer "B.Fab")
		)
		(fp_line
			(start 0.2794 0.9906)
			(end -0.2794 0.9906)
			(stroke
				(width 0.1)
				(type default)
			)
			(layer "B.Fab")
		)
		(pad "1" smd rect
			(at 0 0 180)
			(size 0.508 0.508)
			(layers "B.Cu" "B.Mask" "B.Paste")
			(net "P3V3_STBY")
		)
		(pad "2" smd rect
			(at 0 0.889 180)
			(size 0.508 0.508)
			(layers "B.Cu" "B.Mask" "B.Paste")
			(net "PWRGD_P5V_N")
		)
		(zone
			(layer "B.Cu")
			(hatch none 0.5)
			(connect_pads
				(clearance 0)
			)
			(min_thickness 0.25)
			(keepout
				(tracks allowed)
				(vias not_allowed)
				(pads allowed)
				(copperpour not_allowed)
				(footprints allowed)
			)
			(placement
				(enabled no)
				(sheetname "")
			)
			(fill
				(thermal_gap 0.5)
				(thermal_bridge_width 0.5)
				(island_removal_mode 0)
			)
			(polygon
				(pts
					(xy 412.115 -6.2865) (xy 411.607 -6.2865) (xy 411.607 -5.9055) (xy 412.115 -5.9055)
				)
			)
		)
		(zone
			(layer "B.Cu")
			(hatch none 0.5)
			(connect_pads
				(clearance 0)
			)
			(min_thickness 0.25)
			(keepout
				(tracks not_allowed)
				(vias allowed)
				(pads allowed)
				(copperpour not_allowed)
				(footprints allowed)
			)
			(placement
				(enabled no)
				(sheetname "")
			)
			(fill
				(thermal_gap 0.5)
				(thermal_bridge_width 0.5)
				(island_removal_mode 0)
			)
			(polygon
				(pts
					(xy 412.115 -5.9055) (xy 411.607 -5.9055) (xy 411.607 -6.2865) (xy 412.115 -6.2865)
				)
			)
		)
	)
	(footprint ""
		(layer "B.Cu")
		(at 372.351046 -75.4888)
		(property "Reference" "C3P47"
			(at 0 0 0)
			(layer "B.SilkS")
			(hide yes)
			(effects
				(font
					(size 1.27 1.27)
				)
				(justify mirror)
			)
		)
		(property "Value" ""
			(at 0 0 0)
			(layer "B.Fab")
			(effects
				(font
					(size 1.27 1.27)
				)
				(justify mirror)
			)
		)
		(duplicate_pad_numbers_are_jumpers no)
		(fp_rect
			(start 0.2794 0.9144)
			(end -0.2794 -0.1143)
			(stroke
				(width 0)
				(type default)
			)
			(fill no)
			(layer "B.CrtYd")
		)
		(fp_line
			(start -0.2794 -0.1143)
			(end -0.2794 0.9144)
			(stroke
				(width 0.1)
				(type default)
			)
			(layer "B.Fab")
		)
		(fp_line
			(start -0.2794 0.9144)
			(end 0.2794 0.9144)
			(stroke
				(width 0.1)
				(type default)
			)
			(layer "B.Fab")
		)
		(fp_line
			(start 0.2794 -0.1143)
			(end -0.2794 -0.1143)
			(stroke
				(width 0.1)
				(type default)
			)
			(layer "B.Fab")
		)
		(fp_line
			(start 0.2794 0.9144)
			(end 0.2794 -0.1143)
			(stroke
				(width 0.1)
				(type default)
			)
			(layer "B.Fab")
		)
		(pad "1" smd custom
			(at 0 0 270)
			(size 0.10414 0.10414)
			(layers "B.Cu" "B.Mask" "B.Paste")
			(net "P3V3_STBY")
			(options
				(clearance outline)
				(anchor circle)
			)
			(primitives
				(gr_poly
					(pts
						(xy -0.20828 -0.08636) (xy -0.20828 0.08636) (xy -0.08636 0.20828) (xy 0.086614 0.20828) (xy 0.20828 0.086614)
						(xy 0.20828 -0.08636) (xy 0.08636 -0.20828) (xy -0.08636 -0.20828)
					)
					(width 0)
					(fill yes)
				)
			)
		)
		(pad "2" smd custom
			(at 0 0.8001 270)
			(size 0.10414 0.10414)
			(layers "B.Cu" "B.Mask" "B.Paste")
			(net "GND")
			(options
				(clearance outline)
				(anchor circle)
			)
			(primitives
				(gr_poly
					(pts
						(xy -0.20828 -0.08636) (xy -0.20828 0.08636) (xy -0.08636 0.20828) (xy 0.086614 0.20828) (xy 0.20828 0.086614)
						(xy 0.20828 -0.08636) (xy 0.08636 -0.20828) (xy -0.08636 -0.20828)
					)
					(width 0)
					(fill yes)
				)
			)
		)
		(zone
			(layer "B.Cu")
			(hatch none 0.5)
			(connect_pads
				(clearance 0)
			)
			(min_thickness 0.25)
			(keepout
				(tracks not_allowed)
				(vias allowed)
				(pads allowed)
				(copperpour not_allowed)
				(footprints allowed)
			)
			(placement
				(enabled no)
				(sheetname "")
			)
			(fill
				(thermal_gap 0.5)
				(thermal_bridge_width 0.5)
				(island_removal_mode 0)
			)
			(polygon
				(pts
					(xy 372.438676 -75.27925) (xy 372.438676 -74.89825) (xy 372.263416 -74.89825) (xy 372.263162 -75.27925)
				)
			)
		)
		(zone
			(layer "B.Cu")
			(hatch none 0.5)
			(connect_pads
				(clearance 0)
			)
			(min_thickness 0.25)
			(keepout
				(tracks allowed)
				(vias not_allowed)
				(pads allowed)
				(copperpour not_allowed)
				(footprints allowed)
			)
			(placement
				(enabled no)
				(sheetname "")
			)
			(fill
				(thermal_gap 0.5)
				(thermal_bridge_width 0.5)
				(island_removal_mode 0)
			)
			(polygon
				(pts
					(xy 372.438676 -75.27925) (xy 372.438676 -74.89825) (xy 372.263416 -74.89825) (xy 372.263162 -75.27925)
				)
			)
		)
	)
)
